(kicad_pcb
	(version 20260206)
	(generator "pcbnew")
	(generator_version "10.0")
	(general
		(thickness 1.6)
		(legacy_teardrops no)
	)
	(paper "A4")
	(title_block
		(title "ptb — Lightning_PTB_BRD.brd")
		(comment 1 "Lightning (Wiwynn / Facebook NVMe JBOF) / footprints 57-61 of 61")
	)
	(layers
		(0 "F.Cu" signal "TOP")
		(4 "In1.Cu" signal "L2GND")
		(6 "In2.Cu" signal "L3VCC")
		(2 "B.Cu" signal "BOTTOM")
		(9 "F.Adhes" user "F.Adhesive")
		(11 "B.Adhes" user "B.Adhesive")
		(13 "F.Paste" user "Package Geometry/Pastemask Top")
		(15 "B.Paste" user "Package Geometry/Pastemask Bottom")
		(5 "F.SilkS" user "Ref Des/Silkscreen Top")
		(7 "B.SilkS" user "Ref Des/Silkscreen Bottom")
		(1 "F.Mask" user "Board Geometry/Soldermask Top")
		(3 "B.Mask" user "Board Geometry/Soldermask Bottom")
		(17 "Dwgs.User" user "User.Drawings")
		(19 "Cmts.User" user "User.Comments")
		(21 "Eco1.User" user "User.Eco1")
		(23 "Eco2.User" user "User.Eco2")
		(25 "Edge.Cuts" user "Board Geometry/Outline")
		(27 "Margin" user)
		(31 "F.CrtYd" user "Package Geometry/Place Bound Top")
		(29 "B.CrtYd" user "Package Geometry/Place Bound Bottom")
		(35 "F.Fab" user "Ref Des/Assembly Top")
		(33 "B.Fab" user "Ref Des/Assembly Bottom")
	)
	(footprint ""
		(layer "F.Cu")
		(at 161.159952 -18.999962 180)
		(property "Reference" "LED1"
			(at 0 0 180)
			(layer "F.SilkS")
			(hide yes)
			(effects
				(font
					(size 1.27 1.27)
				)
			)
		)
		(property "Value" "LED-G-203-GP"
			(at -2.6924 -1.4224 180)
			(unlocked yes)
			(layer "F.Fab")
			(hide yes)
			(effects
				(font
					(size 1.016 1.016)
					(thickness 0.1524)
				)
			)
		)
		(property "Device Type" "LED1608AKH26"
			(at -2.6924 -2.9464 180)
			(unlocked yes)
			(layer "F.Fab")
			(hide yes)
			(effects
				(font
					(size 1.016 1.016)
					(thickness 0.1524)
				)
			)
		)
		(duplicate_pad_numbers_are_jumpers no)
		(fp_line
			(start 0.7493 1.651)
			(end 0.7493 1.1811)
			(stroke
				(width 0.3302)
				(type default)
			)
			(layer "F.SilkS")
		)
		(fp_line
			(start 0.6604 1.3716)
			(end -0.6604 1.3716)
			(stroke
				(width 0.1524)
				(type default)
			)
			(layer "F.SilkS")
		)
		(fp_line
			(start 0.6604 -1.3716)
			(end 0.6604 1.3716)
			(stroke
				(width 0.1524)
				(type default)
			)
			(layer "F.SilkS")
		)
		(fp_line
			(start -0.5969 1.5494)
			(end 0.5842 1.5494)
			(stroke
				(width 0.508)
				(type default)
			)
			(layer "F.SilkS")
		)
		(fp_line
			(start -0.6604 1.3716)
			(end -0.6604 -1.3716)
			(stroke
				(width 0.1524)
				(type default)
			)
			(layer "F.SilkS")
		)
		(fp_line
			(start -0.6604 -1.3716)
			(end 0.6604 -1.3716)
			(stroke
				(width 0.1524)
				(type default)
			)
			(layer "F.SilkS")
		)
		(fp_line
			(start -0.7493 1.651)
			(end -0.7493 1.1811)
			(stroke
				(width 0.3302)
				(type default)
			)
			(layer "F.SilkS")
		)
		(fp_rect
			(start -0.6223 1.3335)
			(end 0.6223 -1.3335)
			(stroke
				(width 0)
				(type default)
			)
			(fill no)
			(layer "F.CrtYd")
		)
		(fp_rect
			(start -0.6223 1.3335)
			(end 0.6223 -1.3335)
			(stroke
				(width 0)
				(type default)
			)
			(fill no)
			(layer "F.Fab")
		)
		(pad "A" smd custom
			(at 0 -0.762 180)
			(size 0.2159 0.2159)
			(layers "F.Cu" "F.Mask" "F.Paste")
			(net "TPS2490_LED")
			(options
				(clearance outline)
				(anchor circle)
			)
			(primitives
				(gr_poly
					(pts
						(arc
							(start -0.3302 -0.4318)
							(mid -0.402042 -0.402042)
							(end -0.4318 -0.3302)
						)
						(arc
							(start -0.4318 0.3302)
							(mid -0.402042 0.402042)
							(end -0.3302 0.4318)
						)
						(arc
							(start 0.3302 0.4318)
							(mid 0.402042 0.402042)
							(end 0.4318 0.3302)
						)
						(arc
							(start 0.4318 -0.3302)
							(mid 0.402042 -0.402042)
							(end 0.3302 -0.4318)
						)
					)
					(width 0)
					(fill yes)
				)
			)
		)
		(pad "K" smd custom
			(at 0 0.762 180)
			(size 0.2159 0.2159)
			(layers "F.Cu" "F.Mask" "F.Paste")
			(net "GND")
			(options
				(clearance outline)
				(anchor circle)
			)
			(primitives
				(gr_poly
					(pts
						(arc
							(start -0.3302 -0.4318)
							(mid -0.402042 -0.402042)
							(end -0.4318 -0.3302)
						)
						(arc
							(start -0.4318 0.3302)
							(mid -0.402042 0.402042)
							(end -0.3302 0.4318)
						)
						(arc
							(start 0.3302 0.4318)
							(mid 0.402042 0.402042)
							(end 0.4318 0.3302)
						)
						(arc
							(start 0.4318 -0.3302)
							(mid 0.402042 -0.402042)
							(end 0.3302 -0.4318)
						)
					)
					(width 0)
					(fill yes)
				)
			)
		)
	)
	(footprint ""
		(layer "F.Cu")
		(at 17.2339 -96.071944 90)
		(property "Reference" "R487"
			(at 0 0 90)
			(layer "F.SilkS")
			(hide yes)
			(effects
				(font
					(size 1.27 1.27)
				)
			)
		)
		(property "Value" "0R2J-2-GP"
			(at 0.064008 -3.993896 90)
			(unlocked yes)
			(layer "F.Fab")
			(hide yes)
			(effects
				(font
					(size 1.016 1.016)
					(thickness 0.1524)
				)
			)
		)
		(property "Device Type" "R402H16"
			(at 0.064008 -5.517896 90)
			(unlocked yes)
			(layer "F.Fab")
			(hide yes)
			(effects
				(font
					(size 1.016 1.016)
					(thickness 0.1524)
				)
			)
		)
		(duplicate_pad_numbers_are_jumpers no)
		(fp_line
			(start 0.508 -0.9398)
			(end -0.508 -0.9398)
			(stroke
				(width 0.1524)
				(type default)
			)
			(layer "F.SilkS")
		)
		(fp_line
			(start -0.508 -0.9398)
			(end -0.508 0.9398)
			(stroke
				(width 0.1524)
				(type default)
			)
			(layer "F.SilkS")
		)
		(fp_rect
			(start -0.508 0.9398)
			(end 0.508 -0.9398)
			(stroke
				(width 0)
				(type default)
			)
			(fill no)
			(layer "F.CrtYd")
		)
		(fp_rect
			(start -0.508 0.9398)
			(end 0.508 -0.9398)
			(stroke
				(width 0)
				(type default)
			)
			(fill no)
			(layer "F.Fab")
		)
		(pad "1" smd custom
			(at 0 -0.4445 90)
			(size 0.1397 0.1397)
			(layers "F.Cu" "F.Mask" "F.Paste")
			(net "I2C_C_BUF_SDAIN")
			(options
				(clearance outline)
				(anchor circle)
			)
			(primitives
				(gr_poly
					(pts
						(arc
							(start -0.1778 -0.2794)
							(mid -0.249642 -0.249642)
							(end -0.2794 -0.1778)
						)
						(arc
							(start -0.2794 0.1778)
							(mid -0.249642 0.249642)
							(end -0.1778 0.2794)
						)
						(arc
							(start 0.1778 0.2794)
							(mid 0.249642 0.249642)
							(end 0.2794 0.1778)
						)
						(arc
							(start 0.2794 -0.1778)
							(mid 0.249642 -0.249642)
							(end 0.1778 -0.2794)
						)
					)
					(width 0)
					(fill yes)
				)
			)
		)
		(pad "2" smd custom
			(at 0 0.4445 90)
			(size 0.1397 0.1397)
			(layers "F.Cu" "F.Mask" "F.Paste")
			(net "I2C_C_BUF_SDA")
			(options
				(clearance outline)
				(anchor circle)
			)
			(primitives
				(gr_poly
					(pts
						(arc
							(start -0.1778 -0.2794)
							(mid -0.249642 -0.249642)
							(end -0.2794 -0.1778)
						)
						(arc
							(start -0.2794 0.1778)
							(mid -0.249642 0.249642)
							(end -0.1778 0.2794)
						)
						(arc
							(start 0.1778 0.2794)
							(mid 0.249642 0.249642)
							(end 0.2794 0.1778)
						)
						(arc
							(start 0.2794 -0.1778)
							(mid 0.249642 -0.249642)
							(end 0.1778 -0.2794)
						)
					)
					(width 0)
					(fill yes)
				)
			)
		)
	)
	(footprint ""
		(layer "F.Cu")
		(at 126.659894 -5.999988)
		(property "Reference" "H4"
			(at 0 0 0)
			(layer "F.SilkS")
			(hide yes)
			(effects
				(font
					(size 1.27 1.27)
				)
			)
		)
		(property "Value" "HOLE"
			(at -18.200878 0.089916 0)
			(unlocked yes)
			(layer "F.Fab")
			(hide yes)
			(effects
				(font
					(size 1.016 1.016)
					(thickness 0.1524)
				)
			)
		)
		(property "Device Type" "HOLET827X355B355R158-S"
			(at -18.200878 -1.434084 0)
			(unlocked yes)
			(layer "F.Fab")
			(hide yes)
			(effects
				(font
					(size 1.016 1.016)
					(thickness 0.1524)
				)
			)
		)
		(duplicate_pad_numbers_are_jumpers no)
		(fp_poly
			(pts
				(arc
					(start 4.8133 0)
					(mid -4.8133 0)
					(end 4.8133 0)
				)
			)
			(stroke
				(width 0)
				(type default)
			)
			(fill no)
			(layer "B.CrtYd")
		)
		(fp_poly
			(pts
				(arc
					(start -11.9888 4.8133)
					(mid -16.8021 0)
					(end -11.9888 -4.8133)
				)
				(arc
					(start 0 -4.8133)
					(mid 4.8133 0)
					(end 0 4.8133)
				)
			)
			(stroke
				(width 0)
				(type default)
			)
			(fill no)
			(layer "F.CrtYd")
		)
		(fp_poly
			(pts
				(arc
					(start 4.8133 0)
					(mid -4.8133 0)
					(end 4.8133 0)
				)
			)
			(stroke
				(width 0)
				(type default)
			)
			(fill no)
			(layer "B.Fab")
		)
		(fp_poly
			(pts
				(arc
					(start -11.9888 4.8133)
					(mid -16.8021 0)
					(end -11.9888 -4.8133)
				)
				(arc
					(start 0 -4.8133)
					(mid 4.8133 0)
					(end 0 4.8133)
				)
			)
			(stroke
				(width 0)
				(type default)
			)
			(fill no)
			(layer "F.Fab")
		)
		(pad "1" thru_hole oval
			(at 0 0)
			(size 21.0058 9.017)
			(drill 4.0132
				(offset -5.9944 0)
			)
			(layers "*.Cu" "*.Mask")
			(remove_unused_layers no)
			(net "GND")
			(clearance -7.9883)
			(thermal_gap 0.3048)
			(padstack
				(mode front_inner_back)
				(layer "Inner"
					(shape circle)
					(size 4.4196 4.4196)
					(clearance 0.3048)
				)
				(layer "B.Cu"
					(shape circle)
					(size 9.017 9.017)
					(clearance -1.9939)
				)
			)
		)
	)
	(footprint ""
		(layer "F.Cu")
		(at 135.111744 -82.906108 90)
		(property "Reference" "R374"
			(at 0 0 90)
			(layer "F.SilkS")
			(hide yes)
			(effects
				(font
					(size 1.27 1.27)
				)
			)
		)
		(property "Value" "470KR2F-GP"
			(at 0.064008 -3.993896 90)
			(unlocked yes)
			(layer "F.Fab")
			(hide yes)
			(effects
				(font
					(size 1.016 1.016)
					(thickness 0.1524)
				)
			)
		)
		(property "Device Type" "R402H16"
			(at 0.064008 -5.517896 90)
			(unlocked yes)
			(layer "F.Fab")
			(hide yes)
			(effects
				(font
					(size 1.016 1.016)
					(thickness 0.1524)
				)
			)
		)
		(duplicate_pad_numbers_are_jumpers no)
		(fp_line
			(start 0.508 -0.9398)
			(end -0.508 -0.9398)
			(stroke
				(width 0.1524)
				(type default)
			)
			(layer "F.SilkS")
		)
		(fp_line
			(start -0.508 -0.9398)
			(end -0.508 0.9398)
			(stroke
				(width 0.1524)
				(type default)
			)
			(layer "F.SilkS")
		)
		(fp_rect
			(start -0.508 0.9398)
			(end 0.508 -0.9398)
			(stroke
				(width 0)
				(type default)
			)
			(fill no)
			(layer "F.CrtYd")
		)
		(fp_rect
			(start -0.508 0.9398)
			(end 0.508 -0.9398)
			(stroke
				(width 0)
				(type default)
			)
			(fill no)
			(layer "F.Fab")
		)
		(pad "1" smd custom
			(at 0 -0.4445 90)
			(size 0.1397 0.1397)
			(layers "F.Cu" "F.Mask" "F.Paste")
			(net "TRAY PRESENT_OUT_NET")
			(options
				(clearance outline)
				(anchor circle)
			)
			(primitives
				(gr_poly
					(pts
						(arc
							(start -0.1778 -0.2794)
							(mid -0.249642 -0.249642)
							(end -0.2794 -0.1778)
						)
						(arc
							(start -0.2794 0.1778)
							(mid -0.249642 0.249642)
							(end -0.1778 0.2794)
						)
						(arc
							(start 0.1778 0.2794)
							(mid 0.249642 0.249642)
							(end 0.2794 0.1778)
						)
						(arc
							(start 0.2794 -0.1778)
							(mid 0.249642 -0.249642)
							(end 0.1778 -0.2794)
						)
					)
					(width 0)
					(fill yes)
				)
			)
		)
		(pad "2" smd custom
			(at 0 0.4445 90)
			(size 0.1397 0.1397)
			(layers "F.Cu" "F.Mask" "F.Paste")
			(net "GND")
			(options
				(clearance outline)
				(anchor circle)
			)
			(primitives
				(gr_poly
					(pts
						(arc
							(start -0.1778 -0.2794)
							(mid -0.249642 -0.249642)
							(end -0.2794 -0.1778)
						)
						(arc
							(start -0.2794 0.1778)
							(mid -0.249642 0.249642)
							(end -0.1778 0.2794)
						)
						(arc
							(start 0.1778 0.2794)
							(mid 0.249642 0.249642)
							(end 0.2794 0.1778)
						)
						(arc
							(start 0.2794 -0.1778)
							(mid 0.249642 -0.249642)
							(end 0.1778 -0.2794)
						)
					)
					(width 0)
					(fill yes)
				)
			)
		)
	)
	(footprint ""
		(layer "F.Cu")
		(at 137.795 -69.080634 180)
		(property "Reference" "C360"
			(at 0 0 180)
			(layer "F.SilkS")
			(hide yes)
			(effects
				(font
					(size 1.27 1.27)
				)
			)
		)
		(property "Value" "SC220P50V3JN-GP"
			(at 0 -2.8194 180)
			(unlocked yes)
			(layer "F.Fab")
			(hide yes)
			(effects
				(font
					(size 1.016 1.016)
					(thickness 0.1524)
				)
			)
		)
		(property "Device Type" "C603H36"
			(at 0 -4.3434 180)
			(unlocked yes)
			(layer "F.Fab")
			(hide yes)
			(effects
				(font
					(size 1.016 1.016)
					(thickness 0.1524)
				)
			)
		)
		(duplicate_pad_numbers_are_jumpers no)
		(fp_line
			(start 0.508 0)
			(end -0.508 0)
			(stroke
				(width 0.2032)
				(type default)
			)
			(layer "F.SilkS")
		)
		(fp_rect
			(start -0.5842 1.3335)
			(end 0.5842 -1.3335)
			(stroke
				(width 0)
				(type default)
			)
			(fill no)
			(layer "F.CrtYd")
		)
		(fp_rect
			(start -0.5842 1.3335)
			(end 0.5842 -1.3335)
			(stroke
				(width 0)
				(type default)
			)
			(fill no)
			(layer "F.Fab")
		)
		(pad "1" smd custom
			(at 0 -0.762 180)
			(size 0.2159 0.2159)
			(layers "F.Cu" "F.Mask" "F.Paste")
			(net "I2C_C_BUF_SDA_CONN")
			(options
				(clearance outline)
				(anchor circle)
			)
			(primitives
				(gr_poly
					(pts
						(arc
							(start -0.3302 -0.4318)
							(mid -0.402042 -0.402042)
							(end -0.4318 -0.3302)
						)
						(arc
							(start -0.4318 0.3302)
							(mid -0.402042 0.402042)
							(end -0.3302 0.4318)
						)
						(arc
							(start 0.3302 0.4318)
							(mid 0.402042 0.402042)
							(end 0.4318 0.3302)
						)
						(arc
							(start 0.4318 -0.3302)
							(mid 0.402042 -0.402042)
							(end 0.3302 -0.4318)
						)
					)
					(width 0)
					(fill yes)
				)
			)
		)
		(pad "2" smd custom
			(at 0 0.762 180)
			(size 0.2159 0.2159)
			(layers "F.Cu" "F.Mask" "F.Paste")
			(net "GND")
			(options
				(clearance outline)
				(anchor circle)
			)
			(primitives
				(gr_poly
					(pts
						(arc
							(start -0.3302 -0.4318)
							(mid -0.402042 -0.402042)
							(end -0.4318 -0.3302)
						)
						(arc
							(start -0.4318 0.3302)
							(mid -0.402042 0.402042)
							(end -0.3302 0.4318)
						)
						(arc
							(start 0.3302 0.4318)
							(mid 0.402042 0.402042)
							(end 0.4318 0.3302)
						)
						(arc
							(start 0.4318 -0.3302)
							(mid 0.402042 -0.402042)
							(end 0.3302 -0.4318)
						)
					)
					(width 0)
					(fill yes)
				)
			)
		)
	)
)
